(kicad_pcb
	(version 20260206)
	(generator "pcbnew")
	(generator_version "10.0")
	(general
		(thickness 1.6)
		(legacy_teardrops no)
	)
	(paper "A4")
	(title_block
		(title "01162023_DA0F0TEBIF0_F0T_Expander_BD_F_brd_V02_OCP.brd")
		(comment 1 "Grand Teton / footprints 8229-8234 of 9728")
	)
	(layers
		(0 "F.Cu" signal "TOP")
		(4 "In1.Cu" signal "GND")
		(6 "In2.Cu" signal "VCC")
		(8 "In3.Cu" signal "VCC1")
		(10 "In4.Cu" signal "GND1")
		(12 "In5.Cu" signal "IN1")
		(14 "In6.Cu" signal "GND2")
		(16 "In7.Cu" signal "IN2")
		(18 "In8.Cu" signal "GND3")
		(20 "In9.Cu" signal "IN3")
		(22 "In10.Cu" signal "GND4")
		(24 "In11.Cu" signal "IN4")
		(26 "In12.Cu" signal "GND5")
		(28 "In13.Cu" signal "IN5")
		(30 "In14.Cu" signal "GND6")
		(32 "In15.Cu" signal "IN6")
		(34 "In16.Cu" signal "GND7")
		(2 "B.Cu" signal "BOTTOM")
		(9 "F.Adhes" user "F.Adhesive")
		(11 "B.Adhes" user "B.Adhesive")
		(13 "F.Paste" user "Package Geometry/Pastemask Top")
		(15 "B.Paste" user "Package Geometry/Pastemask Bottom")
		(5 "F.SilkS" user "Ref Des/Silkscreen Top")
		(7 "B.SilkS" user "Ref Des/Silkscreen Bottom")
		(1 "F.Mask" user "Board Geometry/Soldermask Top")
		(3 "B.Mask" user "Board Geometry/Soldermask Bottom")
		(17 "Dwgs.User" user "User.Drawings")
		(19 "Cmts.User" user "User.Comments")
		(21 "Eco1.User" user "User.Eco1")
		(23 "Eco2.User" user "User.Eco2")
		(25 "Edge.Cuts" user "Board Geometry/Outline")
		(27 "Margin" user)
		(31 "F.CrtYd" user "Package Geometry/Place Bound Top")
		(29 "B.CrtYd" user "Package Geometry/Place Bound Bottom")
		(35 "F.Fab" user "Ref Des/Assembly Top")
		(33 "B.Fab" user "Ref Des/Assembly Bottom")
	)
	(footprint ""
		(layer "B.Cu")
		(at 284.724856 -286.399732 90)
		(property "Reference" "C3331"
			(at 0 0 90)
			(layer "B.SilkS")
			(hide yes)
			(effects
				(font
					(size 1.27 1.27)
				)
				(justify mirror)
			)
		)
		(property "Value" ""
			(at 0 0 90)
			(layer "B.Fab")
			(effects
				(font
					(size 1.27 1.27)
				)
				(justify mirror)
			)
		)
		(duplicate_pad_numbers_are_jumpers no)
		(fp_line
			(start 0.299974 -0.150114)
			(end -0.299974 -0.150114)
			(stroke
				(width 0.1)
				(type default)
			)
			(layer "B.Fab")
		)
		(fp_line
			(start -0.299974 -0.150114)
			(end -0.299974 0.150114)
			(stroke
				(width 0.1)
				(type default)
			)
			(layer "B.Fab")
		)
		(fp_line
			(start 0.299974 0.150114)
			(end 0.299974 -0.150114)
			(stroke
				(width 0.1)
				(type default)
			)
			(layer "B.Fab")
		)
		(fp_line
			(start -0.299974 0.150114)
			(end 0.299974 0.150114)
			(stroke
				(width 0.1)
				(type default)
			)
			(layer "B.Fab")
		)
		(pad "1" smd rect
			(at 0.2667 0 270)
			(size 0.3048 0.381)
			(layers "B.Cu" "B.Mask" "B.Paste")
			(net "P1V25_SERDES_VDDPLL_PEX2")
		)
		(pad "2" smd rect
			(at -0.2667 0 270)
			(size 0.3048 0.381)
			(layers "B.Cu" "B.Mask" "B.Paste")
			(net "GND")
		)
	)
	(footprint ""
		(layer "B.Cu")
		(at 292.79977 -303.499774 -90)
		(property "Reference" "C3259"
			(at 0 0 90)
			(layer "B.SilkS")
			(hide yes)
			(effects
				(font
					(size 1.27 1.27)
				)
				(justify mirror)
			)
		)
		(property "Value" ""
			(at 0 0 90)
			(layer "B.Fab")
			(effects
				(font
					(size 1.27 1.27)
				)
				(justify mirror)
			)
		)
		(duplicate_pad_numbers_are_jumpers no)
		(fp_line
			(start -0.299974 0.150114)
			(end 0.299974 0.150114)
			(stroke
				(width 0.1)
				(type default)
			)
			(layer "B.Fab")
		)
		(fp_line
			(start 0.299974 0.150114)
			(end 0.299974 -0.150114)
			(stroke
				(width 0.1)
				(type default)
			)
			(layer "B.Fab")
		)
		(fp_line
			(start -0.299974 -0.150114)
			(end -0.299974 0.150114)
			(stroke
				(width 0.1)
				(type default)
			)
			(layer "B.Fab")
		)
		(fp_line
			(start 0.299974 -0.150114)
			(end -0.299974 -0.150114)
			(stroke
				(width 0.1)
				(type default)
			)
			(layer "B.Fab")
		)
		(pad "1" smd rect
			(at 0.2667 0 90)
			(size 0.3048 0.381)
			(layers "B.Cu" "B.Mask" "B.Paste")
			(net "P1V25_PEX2")
		)
		(pad "2" smd rect
			(at -0.2667 0 90)
			(size 0.3048 0.381)
			(layers "B.Cu" "B.Mask" "B.Paste")
			(net "GND")
		)
	)
	(footprint ""
		(layer "B.Cu")
		(at 255.335024 10.623804 180)
		(property "Reference" "DE16T_3"
			(at -2.525776 -3.068066 0)
			(unlocked yes)
			(layer "B.SilkS")
			(effects
				(font
					(size 0.7874 0.5842)
					(thickness 0.1524)
				)
				(justify left mirror)
			)
		)
		(property "Value" ""
			(at 0 0 0)
			(layer "B.Fab")
			(effects
				(font
					(size 1.27 1.27)
				)
				(justify mirror)
			)
		)
		(duplicate_pad_numbers_are_jumpers no)
		(fp_line
			(start 1.2192 2.1082)
			(end 1.2192 -2.1082)
			(stroke
				(width 0.1524)
				(type default)
			)
			(layer "B.SilkS")
		)
		(fp_line
			(start 1.2192 -2.1082)
			(end -1.2192 -2.1082)
			(stroke
				(width 0.1524)
				(type default)
			)
			(layer "B.SilkS")
		)
		(fp_line
			(start -1.2192 2.1082)
			(end 1.2192 2.1082)
			(stroke
				(width 0.1524)
				(type default)
			)
			(layer "B.SilkS")
		)
		(fp_line
			(start -1.2192 -2.1082)
			(end -1.2192 2.1082)
			(stroke
				(width 0.1524)
				(type default)
			)
			(layer "B.SilkS")
		)
		(pad "" np_thru_hole circle
			(at -3.4671 -1.27 90)
			(size 1.0414 1.0414)
			(drill 1.0414)
			(layers "*.Cu" "*.Mask")
			(clearance 0.381)
			(thermal_gap 0.381)
		)
		(pad "" np_thru_hole circle
			(at -3.4671 1.27 90)
			(size 1.0414 1.0414)
			(drill 1.0414)
			(layers "*.Cu" "*.Mask")
			(clearance 0.381)
			(thermal_gap 0.381)
		)
		(pad "" np_thru_hole circle
			(at 2.8829 -1.27 90)
			(size 1.0414 1.0414)
			(drill 1.0414)
			(layers "*.Cu" "*.Mask")
			(clearance 0.381)
			(thermal_gap 0.381)
		)
		(pad "" np_thru_hole circle
			(at 2.8829 1.27 90)
			(size 1.0414 1.0414)
			(drill 1.0414)
			(layers "*.Cu" "*.Mask")
			(clearance 0.381)
			(thermal_gap 0.381)
		)
		(pad "1" smd rect
			(at -0.8255 -0.249936 90)
			(size 0.3048 0.508)
			(layers "B.Cu" "B.Mask" "B.Paste")
			(net "85_10INCH_IN6_DP")
		)
		(pad "2" smd rect
			(at -0.8255 0.249936 90)
			(size 0.3048 0.508)
			(layers "B.Cu" "B.Mask" "B.Paste")
			(net "85_10INCH_IN6_DN")
		)
		(pad "3" smd circle
			(at 0 0)
			(size 0 0)
			(layers "B.Cu" "B.Mask" "B.Paste")
			(net "COUPON_GND2")
		)
		(zone
			(layers "F.Cu" "B.Cu" "In1.Cu" "In2.Cu" "In3.Cu" "In4.Cu" "In5.Cu" "In6.Cu"
				"In7.Cu" "In8.Cu" "In9.Cu" "In10.Cu" "In11.Cu" "In12.Cu" "In13.Cu" "In14.Cu"
				"In15.Cu" "In16.Cu"
			)
			(hatch none 0.5)
			(connect_pads
				(clearance 0)
			)
			(min_thickness 0.25)
			(keepout
				(tracks not_allowed)
				(vias allowed)
				(pads allowed)
				(copperpour not_allowed)
				(footprints allowed)
			)
			(placement
				(enabled no)
				(sheetname "")
			)
			(fill
				(thermal_gap 0.5)
				(thermal_bridge_width 0.5)
				(island_removal_mode 0)
			)
			(polygon
				(pts
					(arc
						(start 253.379224 9.353804)
						(mid 251.525024 9.353804)
						(end 253.379224 9.353804)
					)
				)
			)
		)
		(zone
			(layers "F.Cu" "B.Cu" "In1.Cu" "In2.Cu" "In3.Cu" "In4.Cu" "In5.Cu" "In6.Cu"
				"In7.Cu" "In8.Cu" "In9.Cu" "In10.Cu" "In11.Cu" "In12.Cu" "In13.Cu" "In14.Cu"
				"In15.Cu" "In16.Cu"
			)
			(hatch none 0.5)
			(connect_pads
				(clearance 0)
			)
			(min_thickness 0.25)
			(keepout
				(tracks not_allowed)
				(vias allowed)
				(pads allowed)
				(copperpour not_allowed)
				(footprints allowed)
			)
			(placement
				(enabled no)
				(sheetname "")
			)
			(fill
				(thermal_gap 0.5)
				(thermal_bridge_width 0.5)
				(island_removal_mode 0)
			)
			(polygon
				(pts
					(arc
						(start 253.379224 11.893804)
						(mid 251.525024 11.893804)
						(end 253.379224 11.893804)
					)
				)
			)
		)
		(zone
			(layers "F.Cu" "B.Cu" "In1.Cu" "In2.Cu" "In3.Cu" "In4.Cu" "In5.Cu" "In6.Cu"
				"In7.Cu" "In8.Cu" "In9.Cu" "In10.Cu" "In11.Cu" "In12.Cu" "In13.Cu" "In14.Cu"
				"In15.Cu" "In16.Cu"
			)
			(hatch none 0.5)
			(connect_pads
				(clearance 0)
			)
			(min_thickness 0.25)
			(keepout
				(tracks not_allowed)
				(vias allowed)
				(pads allowed)
				(copperpour not_allowed)
				(footprints allowed)
			)
			(placement
				(enabled no)
				(sheetname "")
			)
			(fill
				(thermal_gap 0.5)
				(thermal_bridge_width 0.5)
				(island_removal_mode 0)
			)
			(polygon
				(pts
					(arc
						(start 259.729224 9.353804)
						(mid 257.875024 9.353804)
						(end 259.729224 9.353804)
					)
				)
			)
		)
		(zone
			(layers "F.Cu" "B.Cu" "In1.Cu" "In2.Cu" "In3.Cu" "In4.Cu" "In5.Cu" "In6.Cu"
				"In7.Cu" "In8.Cu" "In9.Cu" "In10.Cu" "In11.Cu" "In12.Cu" "In13.Cu" "In14.Cu"
				"In15.Cu" "In16.Cu"
			)
			(hatch none 0.5)
			(connect_pads
				(clearance 0)
			)
			(min_thickness 0.25)
			(keepout
				(tracks not_allowed)
				(vias allowed)
				(pads allowed)
				(copperpour not_allowed)
				(footprints allowed)
			)
			(placement
				(enabled no)
				(sheetname "")
			)
			(fill
				(thermal_gap 0.5)
				(thermal_bridge_width 0.5)
				(island_removal_mode 0)
			)
			(polygon
				(pts
					(arc
						(start 259.729224 11.893804)
						(mid 257.875024 11.893804)
						(end 259.729224 11.893804)
					)
				)
			)
		)
		(zone
			(layer "B.Cu")
			(hatch none 0.5)
			(connect_pads
				(clearance 0)
			)
			(min_thickness 0.25)
			(keepout
				(tracks not_allowed)
				(vias allowed)
				(pads allowed)
				(copperpour not_allowed)
				(footprints allowed)
			)
			(placement
				(enabled no)
				(sheetname "")
			)
			(fill
				(thermal_gap 0.5)
				(thermal_bridge_width 0.5)
				(island_removal_mode 0)
			)
			(polygon
				(pts
					(xy 256.452624 11.172444) (xy 256.452624 11.07694) (xy 255.855724 11.07694) (xy 255.855724 10.67054)
					(xy 256.452624 10.67054) (xy 256.452624 10.577068) (xy 255.855724 10.577068) (xy 255.855724 10.170668)
					(xy 256.452624 10.170668) (xy 256.452624 10.075164) (xy 255.754124 10.075164) (xy 255.754124 11.172444)
				)
			)
		)
	)
	(footprint ""
		(layer "B.Cu")
		(at 9.078976 -380.957836 90)
		(property "Reference" "C4471"
			(at 0 0 90)
			(layer "B.SilkS")
			(hide yes)
			(effects
				(font
					(size 1.27 1.27)
				)
				(justify mirror)
			)
		)
		(property "Value" ""
			(at 0 0 90)
			(layer "B.Fab")
			(effects
				(font
					(size 1.27 1.27)
				)
				(justify mirror)
			)
		)
		(duplicate_pad_numbers_are_jumpers no)
		(fp_line
			(start 0.7874 -0.4064)
			(end -0.7874 -0.4064)
			(stroke
				(width 0.1524)
				(type default)
			)
			(layer "B.SilkS")
		)
		(fp_line
			(start -0.7874 -0.4064)
			(end -0.7874 0.4064)
			(stroke
				(width 0.1524)
				(type default)
			)
			(layer "B.SilkS")
		)
		(fp_line
			(start 0.7874 0.4064)
			(end 0.7874 -0.4064)
			(stroke
				(width 0.1524)
				(type default)
			)
			(layer "B.SilkS")
		)
		(fp_line
			(start -0.7874 0.4064)
			(end 0.7874 0.4064)
			(stroke
				(width 0.1524)
				(type default)
			)
			(layer "B.SilkS")
		)
		(fp_line
			(start 0.67945 -0.305054)
			(end 0.12065 -0.305054)
			(stroke
				(width 0.1)
				(type default)
			)
			(layer "B.Fab")
		)
		(fp_line
			(start 0.12065 -0.305054)
			(end 0.12065 -0.2794)
			(stroke
				(width 0.1)
				(type default)
			)
			(layer "B.Fab")
		)
		(fp_line
			(start -0.12065 -0.3048)
			(end -0.67945 -0.3048)
			(stroke
				(width 0.1)
				(type default)
			)
			(layer "B.Fab")
		)
		(fp_line
			(start -0.67945 -0.3048)
			(end -0.67945 0.3048)
			(stroke
				(width 0.1)
				(type default)
			)
			(layer "B.Fab")
		)
		(fp_line
			(start 0.12065 -0.2794)
			(end -0.12065 -0.2794)
			(stroke
				(width 0.1)
				(type default)
			)
			(layer "B.Fab")
		)
		(fp_line
			(start -0.12065 -0.2794)
			(end -0.12065 -0.3048)
			(stroke
				(width 0.1)
				(type default)
			)
			(layer "B.Fab")
		)
		(fp_line
			(start 0.12065 0.2794)
			(end 0.12065 0.3048)
			(stroke
				(width 0.1)
				(type default)
			)
			(layer "B.Fab")
		)
		(fp_line
			(start -0.120396 0.2794)
			(end 0.12065 0.2794)
			(stroke
				(width 0.1)
				(type default)
			)
			(layer "B.Fab")
		)
		(fp_line
			(start 0.67945 0.3048)
			(end 0.67945 -0.305054)
			(stroke
				(width 0.1)
				(type default)
			)
			(layer "B.Fab")
		)
		(fp_line
			(start 0.12065 0.3048)
			(end 0.67945 0.3048)
			(stroke
				(width 0.1)
				(type default)
			)
			(layer "B.Fab")
		)
		(fp_line
			(start -0.120396 0.3048)
			(end -0.120396 0.2794)
			(stroke
				(width 0.1)
				(type default)
			)
			(layer "B.Fab")
		)
		(fp_line
			(start -0.67945 0.3048)
			(end -0.120396 0.3048)
			(stroke
				(width 0.1)
				(type default)
			)
			(layer "B.Fab")
		)
		(pad "1" smd circle
			(at 0.40005 0 270)
			(size 0 0)
			(layers "B.Cu" "B.Mask" "B.Paste")
			(net "P1V2_USB_8042")
		)
		(pad "2" smd circle
			(at -0.40005 0 270)
			(size 0 0)
			(layers "B.Cu" "B.Mask" "B.Paste")
			(net "GND")
		)
	)
	(footprint ""
		(layer "B.Cu")
		(at 50.644044 -138.421618 180)
		(property "Reference" "R24"
			(at 0 0 0)
			(layer "B.SilkS")
			(hide yes)
			(effects
				(font
					(size 1.27 1.27)
				)
				(justify mirror)
			)
		)
		(property "Value" ""
			(at 0 0 0)
			(layer "B.Fab")
			(effects
				(font
					(size 1.27 1.27)
				)
				(justify mirror)
			)
		)
		(duplicate_pad_numbers_are_jumpers no)
		(fp_line
			(start 0.7874 0.4064)
			(end 0.7874 -0.4064)
			(stroke
				(width 0.1524)
				(type default)
			)
			(layer "B.SilkS")
		)
		(fp_line
			(start 0.7874 -0.4064)
			(end -0.7874 -0.4064)
			(stroke
				(width 0.1524)
				(type default)
			)
			(layer "B.SilkS")
		)
		(fp_line
			(start -0.7874 0.4064)
			(end 0.7874 0.4064)
			(stroke
				(width 0.1524)
				(type default)
			)
			(layer "B.SilkS")
		)
		(fp_line
			(start -0.7874 -0.4064)
			(end -0.7874 0.4064)
			(stroke
				(width 0.1524)
				(type default)
			)
			(layer "B.SilkS")
		)
		(fp_line
			(start 0.67945 0.3048)
			(end 0.67945 -0.305054)
			(stroke
				(width 0.1)
				(type default)
			)
			(layer "B.Fab")
		)
		(fp_line
			(start 0.67945 -0.305054)
			(end 0.12065 -0.305054)
			(stroke
				(width 0.1)
				(type default)
			)
			(layer "B.Fab")
		)
		(fp_line
			(start 0.12065 0.3048)
			(end 0.67945 0.3048)
			(stroke
				(width 0.1)
				(type default)
			)
			(layer "B.Fab")
		)
		(fp_line
			(start 0.12065 0.2794)
			(end 0.12065 0.3048)
			(stroke
				(width 0.1)
				(type default)
			)
			(layer "B.Fab")
		)
		(fp_line
			(start 0.12065 -0.2794)
			(end -0.12065 -0.2794)
			(stroke
				(width 0.1)
				(type default)
			)
			(layer "B.Fab")
		)
		(fp_line
			(start 0.12065 -0.305054)
			(end 0.12065 -0.2794)
			(stroke
				(width 0.1)
				(type default)
			)
			(layer "B.Fab")
		)
		(fp_line
			(start -0.120396 0.3048)
			(end -0.120396 0.2794)
			(stroke
				(width 0.1)
				(type default)
			)
			(layer "B.Fab")
		)
		(fp_line
			(start -0.120396 0.2794)
			(end 0.12065 0.2794)
			(stroke
				(width 0.1)
				(type default)
			)
			(layer "B.Fab")
		)
		(fp_line
			(start -0.12065 -0.2794)
			(end -0.12065 -0.3048)
			(stroke
				(width 0.1)
				(type default)
			)
			(layer "B.Fab")
		)
		(fp_line
			(start -0.12065 -0.3048)
			(end -0.67945 -0.3048)
			(stroke
				(width 0.1)
				(type default)
			)
			(layer "B.Fab")
		)
		(fp_line
			(start -0.67945 0.3048)
			(end -0.120396 0.3048)
			(stroke
				(width 0.1)
				(type default)
			)
			(layer "B.Fab")
		)
		(fp_line
			(start -0.67945 -0.3048)
			(end -0.67945 0.3048)
			(stroke
				(width 0.1)
				(type default)
			)
			(layer "B.Fab")
		)
		(pad "1" smd circle
			(at 0.40005 0)
			(size 0 0)
			(layers "B.Cu" "B.Mask" "B.Paste")
			(net "NIC0_AUX_PWR_EN")
		)
		(pad "2" smd circle
			(at -0.40005 0)
			(size 0 0)
			(layers "B.Cu" "B.Mask" "B.Paste")
			(net "GND")
		)
	)
	(footprint ""
		(layer "B.Cu")
		(at 110.817914 -325.153528 -90)
		(property "Reference" "C4205"
			(at 0 0 90)
			(layer "B.SilkS")
			(hide yes)
			(effects
				(font
					(size 1.27 1.27)
				)
				(justify mirror)
			)
		)
		(property "Value" ""
			(at 0 0 90)
			(layer "B.Fab")
			(effects
				(font
					(size 1.27 1.27)
				)
				(justify mirror)
			)
		)
		(duplicate_pad_numbers_are_jumpers no)
		(fp_line
			(start -1.2954 0.5842)
			(end 1.2954 0.5842)
			(stroke
				(width 0.1524)
				(type default)
			)
			(layer "B.SilkS")
		)
		(fp_line
			(start 1.2954 0.5842)
			(end 1.2954 -0.5842)
			(stroke
				(width 0.1524)
				(type default)
			)
			(layer "B.SilkS")
		)
		(fp_line
			(start -1.2954 -0.5842)
			(end -1.2954 0.5842)
			(stroke
				(width 0.1524)
				(type default)
			)
			(layer "B.SilkS")
		)
		(fp_line
			(start 1.2954 -0.5842)
			(end -1.2954 -0.5842)
			(stroke
				(width 0.1524)
				(type default)
			)
			(layer "B.SilkS")
		)
		(fp_line
			(start -0.8636 0.4572)
			(end 0.8636 0.4572)
			(stroke
				(width 0.1)
				(type default)
			)
			(layer "B.Fab")
		)
		(fp_line
			(start 0.8636 0.4572)
			(end 0.8636 0.4064)
			(stroke
				(width 0.1)
				(type default)
			)
			(layer "B.Fab")
		)
		(fp_line
			(start -1.1938 0.4064)
			(end -0.8636 0.4064)
			(stroke
				(width 0.1)
				(type default)
			)
			(layer "B.Fab")
		)
		(fp_line
			(start -0.8636 0.4064)
			(end -0.8636 0.4572)
			(stroke
				(width 0.1)
				(type default)
			)
			(layer "B.Fab")
		)
		(fp_line
			(start 0.8636 0.4064)
			(end 1.1938 0.4064)
			(stroke
				(width 0.1)
				(type default)
			)
			(layer "B.Fab")
		)
		(fp_line
			(start 1.1938 0.4064)
			(end 1.1938 -0.4064)
			(stroke
				(width 0.1)
				(type default)
			)
			(layer "B.Fab")
		)
		(fp_line
			(start -1.1938 -0.4064)
			(end -1.1938 0.4064)
			(stroke
				(width 0.1)
				(type default)
			)
			(layer "B.Fab")
		)
		(fp_line
			(start -0.8636 -0.4064)
			(end -1.1938 -0.4064)
			(stroke
				(width 0.1)
				(type default)
			)
			(layer "B.Fab")
		)
		(fp_line
			(start 0.8636 -0.4064)
			(end 0.8636 -0.4572)
			(stroke
				(width 0.1)
				(type default)
			)
			(layer "B.Fab")
		)
		(fp_line
			(start 1.1938 -0.4064)
			(end 0.8636 -0.4064)
			(stroke
				(width 0.1)
				(type default)
			)
			(layer "B.Fab")
		)
		(fp_line
			(start -0.8636 -0.4572)
			(end -0.8636 -0.4064)
			(stroke
				(width 0.1)
				(type default)
			)
			(layer "B.Fab")
		)
		(fp_line
			(start 0.8636 -0.4572)
			(end -0.8636 -0.4572)
			(stroke
				(width 0.1)
				(type default)
			)
			(layer "B.Fab")
		)
		(pad "1" smd rect
			(at 0.7366 0 180)
			(size 0.7112 0.8128)
			(layers "B.Cu" "B.Mask" "B.Paste")
			(net "P0V8_SERDES_VDDA_PEX0_C3")
		)
		(pad "2" smd rect
			(at -0.7366 0 180)
			(size 0.7112 0.8128)
			(layers "B.Cu" "B.Mask" "B.Paste")
			(net "GND")
		)
	)
)
